# T6G (Grand Teton) — schematic netlist excerpt (pin names and nets, part order shuffled) for the footprints in the layout excerpt that follows; sources: Cadence DE-HDL packaged netlist, KiCad conversion of 04192023_DAF0TMB3IC0_F0TG_MB_C_brd_V02_OCP.brd

R6744  Q_RES  1K 1% CHIP  pkg 0402LF  page 358 : A = RT_BOARD_ID_ID1 ; B = GND
R4214  Q_RES  0 5% CHIP  pkg 0402LF  page 235 : A = FM_THERMAL_ALERT_N ; B = FM_G751_1_ALERT_N

(kicad_pcb
	(version 20260206)
	(generator "pcbnew")
	(generator_version "10.0")
	(general
		(thickness 1.6)
		(legacy_teardrops no)
	)
	(paper "A4")
	(title_block
		(title "04192023_DAF0TMB3IC0_F0TG_MB_C_brd_V02_OCP.brd")
		(comment 1 "Grand Teton / footprints 656-657 of 8354")
	)
	(layers
		(0 "F.Cu" signal "TOP")
		(4 "In1.Cu" signal "GND")
		(6 "In2.Cu" signal "IN1")
		(8 "In3.Cu" signal "GND1")
		(10 "In4.Cu" signal "IN2")
		(12 "In5.Cu" signal "GND2")
		(14 "In6.Cu" signal "IN3")
		(16 "In7.Cu" signal "GND3")
		(18 "In8.Cu" signal "VCC")
		(20 "In9.Cu" signal "VCC1")
		(22 "In10.Cu" signal "GND4")
		(24 "In11.Cu" signal "IN4")
		(26 "In12.Cu" signal "GND5")
		(28 "In13.Cu" signal "IN5")
		(30 "In14.Cu" signal "GND6")
		(32 "In15.Cu" signal "IN6")
		(34 "In16.Cu" signal "GND7")
		(2 "B.Cu" signal "BOTTOM")
		(9 "F.Adhes" user "F.Adhesive")
		(11 "B.Adhes" user "B.Adhesive")
		(13 "F.Paste" user "Package Geometry/Pastemask Top")
		(15 "B.Paste" user "Package Geometry/Pastemask Bottom")
		(5 "F.SilkS" user "Ref Des/Silkscreen Top")
		(7 "B.SilkS" user "Ref Des/Silkscreen Bottom")
		(1 "F.Mask" user "Board Geometry/Soldermask Top")
		(3 "B.Mask" user "Board Geometry/Soldermask Bottom")
		(17 "Dwgs.User" user "User.Drawings")
		(19 "Cmts.User" user "User.Comments")
		(21 "Eco1.User" user "User.Eco1")
		(23 "Eco2.User" user "User.Eco2")
		(25 "Edge.Cuts" user "Board Geometry/Outline")
		(27 "Margin" user)
		(31 "F.CrtYd" user "Package Geometry/Place Bound Top")
		(29 "B.CrtYd" user "Package Geometry/Place Bound Bottom")
		(35 "F.Fab" user "Ref Des/Assembly Top")
		(33 "B.Fab" user "Ref Des/Assembly Bottom")
	)
	(footprint ""
		(layer "F.Cu")
		(at 288.393124 -13.360146)
		(property "Reference" "R4214"
			(at 0 0 0)
			(layer "F.SilkS")
			(hide yes)
			(effects
				(font
					(size 1.27 1.27)
				)
			)
		)
		(property "Value" ""
			(at 0 0 0)
			(layer "F.Fab")
			(effects
				(font
					(size 1.27 1.27)
				)
			)
		)
		(duplicate_pad_numbers_are_jumpers no)
		(fp_line
			(start -0.7874 -0.4064)
			(end 0.7874 -0.4064)
			(stroke
				(width 0.1524)
				(type default)
			)
			(layer "F.SilkS")
		)
		(fp_line
			(start -0.7874 0.4064)
			(end -0.7874 -0.4064)
			(stroke
				(width 0.1524)
				(type default)
			)
			(layer "F.SilkS")
		)
		(fp_line
			(start 0.7874 -0.4064)
			(end 0.7874 0.4064)
			(stroke
				(width 0.1524)
				(type default)
			)
			(layer "F.SilkS")
		)
		(fp_line
			(start 0.7874 0.4064)
			(end -0.7874 0.4064)
			(stroke
				(width 0.1524)
				(type default)
			)
			(layer "F.SilkS")
		)
		(fp_line
			(start -0.67945 -0.305054)
			(end -0.12065 -0.305054)
			(stroke
				(width 0.1)
				(type default)
			)
			(layer "F.Fab")
		)
		(fp_line
			(start -0.67945 0.3048)
			(end -0.67945 -0.305054)
			(stroke
				(width 0.1)
				(type default)
			)
			(layer "F.Fab")
		)
		(fp_line
			(start -0.12065 -0.305054)
			(end -0.12065 -0.2794)
			(stroke
				(width 0.1)
				(type default)
			)
			(layer "F.Fab")
		)
		(fp_line
			(start -0.12065 -0.2794)
			(end 0.12065 -0.2794)
			(stroke
				(width 0.1)
				(type default)
			)
			(layer "F.Fab")
		)
		(fp_line
			(start -0.12065 0.2794)
			(end -0.12065 0.3048)
			(stroke
				(width 0.1)
				(type default)
			)
			(layer "F.Fab")
		)
		(fp_line
			(start -0.12065 0.3048)
			(end -0.67945 0.3048)
			(stroke
				(width 0.1)
				(type default)
			)
			(layer "F.Fab")
		)
		(fp_line
			(start 0.120396 0.2794)
			(end -0.12065 0.2794)
			(stroke
				(width 0.1)
				(type default)
			)
			(layer "F.Fab")
		)
		(fp_line
			(start 0.120396 0.3048)
			(end 0.120396 0.2794)
			(stroke
				(width 0.1)
				(type default)
			)
			(layer "F.Fab")
		)
		(fp_line
			(start 0.12065 -0.3048)
			(end 0.67945 -0.3048)
			(stroke
				(width 0.1)
				(type default)
			)
			(layer "F.Fab")
		)
		(fp_line
			(start 0.12065 -0.2794)
			(end 0.12065 -0.3048)
			(stroke
				(width 0.1)
				(type default)
			)
			(layer "F.Fab")
		)
		(fp_line
			(start 0.67945 -0.3048)
			(end 0.67945 0.3048)
			(stroke
				(width 0.1)
				(type default)
			)
			(layer "F.Fab")
		)
		(fp_line
			(start 0.67945 0.3048)
			(end 0.120396 0.3048)
			(stroke
				(width 0.1)
				(type default)
			)
			(layer "F.Fab")
		)
		(pad "1" smd circle
			(at -0.40005 0)
			(size 0 0)
			(layers "F.Cu" "F.Mask" "F.Paste")
			(net "FM_THERMAL_ALERT_N")
		)
		(pad "2" smd circle
			(at 0.40005 0)
			(size 0 0)
			(layers "F.Cu" "F.Mask" "F.Paste")
			(net "FM_G751_1_ALERT_N")
		)
	)
	(footprint ""
		(layer "F.Cu")
		(at 177.67808 -92.685616 -90)
		(property "Reference" "R6744"
			(at 0 0 270)
			(layer "F.SilkS")
			(hide yes)
			(effects
				(font
					(size 1.27 1.27)
				)
			)
		)
		(property "Value" ""
			(at 0 0 270)
			(layer "F.Fab")
			(effects
				(font
					(size 1.27 1.27)
				)
			)
		)
		(duplicate_pad_numbers_are_jumpers no)
		(fp_line
			(start -0.7874 0.4064)
			(end -0.7874 -0.4064)
			(stroke
				(width 0.1524)
				(type default)
			)
			(layer "F.SilkS")
		)
		(fp_line
			(start 0.7874 0.4064)
			(end -0.7874 0.4064)
			(stroke
				(width 0.1524)
				(type default)
			)
			(layer "F.SilkS")
		)
		(fp_line
			(start -0.7874 -0.4064)
			(end 0.7874 -0.4064)
			(stroke
				(width 0.1524)
				(type default)
			)
			(layer "F.SilkS")
		)
		(fp_line
			(start 0.7874 -0.4064)
			(end 0.7874 0.4064)
			(stroke
				(width 0.1524)
				(type default)
			)
			(layer "F.SilkS")
		)
		(fp_line
			(start -0.67945 0.3048)
			(end -0.67945 -0.305054)
			(stroke
				(width 0.1)
				(type default)
			)
			(layer "F.Fab")
		)
		(fp_line
			(start -0.12065 0.3048)
			(end -0.67945 0.3048)
			(stroke
				(width 0.1)
				(type default)
			)
			(layer "F.Fab")
		)
		(fp_line
			(start 0.120396 0.3048)
			(end 0.120396 0.2794)
			(stroke
				(width 0.1)
				(type default)
			)
			(layer "F.Fab")
		)
		(fp_line
			(start 0.67945 0.3048)
			(end 0.120396 0.3048)
			(stroke
				(width 0.1)
				(type default)
			)
			(layer "F.Fab")
		)
		(fp_line
			(start -0.12065 0.2794)
			(end -0.12065 0.3048)
			(stroke
				(width 0.1)
				(type default)
			)
			(layer "F.Fab")
		)
		(fp_line
			(start 0.120396 0.2794)
			(end -0.12065 0.2794)
			(stroke
				(width 0.1)
				(type default)
			)
			(layer "F.Fab")
		)
		(fp_line
			(start -0.12065 -0.2794)
			(end 0.12065 -0.2794)
			(stroke
				(width 0.1)
				(type default)
			)
			(layer "F.Fab")
		)
		(fp_line
			(start 0.12065 -0.2794)
			(end 0.12065 -0.3048)
			(stroke
				(width 0.1)
				(type default)
			)
			(layer "F.Fab")
		)
		(fp_line
			(start 0.12065 -0.3048)
			(end 0.67945 -0.3048)
			(stroke
				(width 0.1)
				(type default)
			)
			(layer "F.Fab")
		)
		(fp_line
			(start 0.67945 -0.3048)
			(end 0.67945 0.3048)
			(stroke
				(width 0.1)
				(type default)
			)
			(layer "F.Fab")
		)
		(fp_line
			(start -0.67945 -0.305054)
			(end -0.12065 -0.305054)
			(stroke
				(width 0.1)
				(type default)
			)
			(layer "F.Fab")
		)
		(fp_line
			(start -0.12065 -0.305054)
			(end -0.12065 -0.2794)
			(stroke
				(width 0.1)
				(type default)
			)
			(layer "F.Fab")
		)
		(pad "1" smd circle
			(at -0.40005 0 270)
			(size 0 0)
			(layers "F.Cu" "F.Mask" "F.Paste")
			(net "RT_BOARD_ID_ID1")
		)
		(pad "2" smd circle
			(at 0.40005 0 270)
			(size 0 0)
			(layers "F.Cu" "F.Mask" "F.Paste")
			(net "GND")
		)
	)
)
